(kicad_pcb
	(version 20260206)
	(generator "pcbnew")
	(generator_version "10.0")
	(general
		(thickness 1.6)
		(legacy_teardrops no)
	)
	(paper "A4")
	(title_block
		(title "dpb — 14545-sa.0730WZS0815.brd")
		(comment 1 "Honey Badger (Wiwynn) / footprints 845-847 of 1066")
	)
	(layers
		(0 "F.Cu" signal "TOP")
		(4 "In1.Cu" signal "L2GND")
		(6 "In2.Cu" signal "L3")
		(8 "In3.Cu" signal "L4VCC")
		(10 "In4.Cu" signal "L5VCC")
		(12 "In5.Cu" signal "L6")
		(14 "In6.Cu" signal "L7GND")
		(2 "B.Cu" signal "BOTTOM")
		(9 "F.Adhes" user "F.Adhesive")
		(11 "B.Adhes" user "B.Adhesive")
		(13 "F.Paste" user "Package Geometry/Pastemask Top")
		(15 "B.Paste" user "Package Geometry/Pastemask Bottom")
		(5 "F.SilkS" user "Ref Des/Silkscreen Top")
		(7 "B.SilkS" user "Ref Des/Silkscreen Bottom")
		(1 "F.Mask" user "Board Geometry/Soldermask Top")
		(3 "B.Mask" user "Board Geometry/Soldermask Bottom")
		(17 "Dwgs.User" user "User.Drawings")
		(19 "Cmts.User" user "User.Comments")
		(21 "Eco1.User" user "User.Eco1")
		(23 "Eco2.User" user "User.Eco2")
		(25 "Edge.Cuts" user "Board Geometry/Outline")
		(27 "Margin" user)
		(31 "F.CrtYd" user "Package Geometry/Place Bound Top")
		(29 "B.CrtYd" user "Package Geometry/Place Bound Bottom")
		(35 "F.Fab" user "Ref Des/Assembly Top")
		(33 "B.Fab" user "Ref Des/Assembly Bottom")
	)
	(footprint ""
		(layer "F.Cu")
		(at 95.757746 -14.4907 90)
		(property "Reference" "R477"
			(at 0 0 90)
			(layer "F.SilkS")
			(hide yes)
			(effects
				(font
					(size 1.27 1.27)
				)
			)
		)
		(property "Value" "4K7R2J-2-GP"
			(at 0.064008 -3.993896 90)
			(unlocked yes)
			(layer "F.Fab")
			(hide yes)
			(effects
				(font
					(size 1.016 1.016)
					(thickness 0.1524)
				)
			)
		)
		(property "Device Type" "R402H16"
			(at 0.064008 -5.517896 90)
			(unlocked yes)
			(layer "F.Fab")
			(hide yes)
			(effects
				(font
					(size 1.016 1.016)
					(thickness 0.1524)
				)
			)
		)
		(duplicate_pad_numbers_are_jumpers no)
		(fp_line
			(start 0.508 -0.9398)
			(end -0.508 -0.9398)
			(stroke
				(width 0.1524)
				(type default)
			)
			(layer "F.SilkS")
		)
		(fp_line
			(start -0.508 -0.9398)
			(end -0.508 0.9398)
			(stroke
				(width 0.1524)
				(type default)
			)
			(layer "F.SilkS")
		)
		(fp_rect
			(start -0.508 0.9398)
			(end 0.508 -0.9398)
			(stroke
				(width 0)
				(type default)
			)
			(fill no)
			(layer "F.CrtYd")
		)
		(fp_rect
			(start -0.508 0.9398)
			(end 0.508 -0.9398)
			(stroke
				(width 0)
				(type default)
			)
			(fill no)
			(layer "F.Fab")
		)
		(pad "1" smd custom
			(at 0 -0.4445 90)
			(size 0.1397 0.1397)
			(layers "F.Cu" "F.Mask" "F.Paste")
			(net "P3V3")
			(options
				(clearance outline)
				(anchor circle)
			)
			(primitives
				(gr_poly
					(pts
						(arc
							(start -0.1778 -0.2794)
							(mid -0.249642 -0.249642)
							(end -0.2794 -0.1778)
						)
						(arc
							(start -0.2794 0.1778)
							(mid -0.249642 0.249642)
							(end -0.1778 0.2794)
						)
						(arc
							(start 0.1778 0.2794)
							(mid 0.249642 0.249642)
							(end 0.2794 0.1778)
						)
						(arc
							(start 0.2794 -0.1778)
							(mid 0.249642 -0.249642)
							(end 0.1778 -0.2794)
						)
					)
					(width 0)
					(fill yes)
				)
			)
		)
		(pad "2" smd custom
			(at 0 0.4445 90)
			(size 0.1397 0.1397)
			(layers "F.Cu" "F.Mask" "F.Paste")
			(net "SAS_EXP_B_PWR14")
			(options
				(clearance outline)
				(anchor circle)
			)
			(primitives
				(gr_poly
					(pts
						(arc
							(start -0.1778 -0.2794)
							(mid -0.249642 -0.249642)
							(end -0.2794 -0.1778)
						)
						(arc
							(start -0.2794 0.1778)
							(mid -0.249642 0.249642)
							(end -0.1778 0.2794)
						)
						(arc
							(start 0.1778 0.2794)
							(mid 0.249642 0.249642)
							(end 0.2794 0.1778)
						)
						(arc
							(start 0.2794 -0.1778)
							(mid 0.249642 -0.249642)
							(end 0.1778 -0.2794)
						)
					)
					(width 0)
					(fill yes)
				)
			)
		)
	)
	(footprint ""
		(layer "F.Cu")
		(at 165.112446 -458.123036 90)
		(property "Reference" "R373"
			(at 0 0 90)
			(layer "F.SilkS")
			(hide yes)
			(effects
				(font
					(size 1.27 1.27)
				)
			)
		)
		(property "Value" "0R2J-2-GP"
			(at 0.064008 -3.993896 90)
			(unlocked yes)
			(layer "F.Fab")
			(hide yes)
			(effects
				(font
					(size 1.016 1.016)
					(thickness 0.1524)
				)
			)
		)
		(property "Device Type" "R402H16"
			(at 0.064008 -5.517896 90)
			(unlocked yes)
			(layer "F.Fab")
			(hide yes)
			(effects
				(font
					(size 1.016 1.016)
					(thickness 0.1524)
				)
			)
		)
		(duplicate_pad_numbers_are_jumpers no)
		(fp_line
			(start 0.508 -0.9398)
			(end -0.508 -0.9398)
			(stroke
				(width 0.1524)
				(type default)
			)
			(layer "F.SilkS")
		)
		(fp_line
			(start -0.508 -0.9398)
			(end -0.508 0.9398)
			(stroke
				(width 0.1524)
				(type default)
			)
			(layer "F.SilkS")
		)
		(fp_rect
			(start -0.508 0.9398)
			(end 0.508 -0.9398)
			(stroke
				(width 0)
				(type default)
			)
			(fill no)
			(layer "F.CrtYd")
		)
		(fp_rect
			(start -0.508 0.9398)
			(end 0.508 -0.9398)
			(stroke
				(width 0)
				(type default)
			)
			(fill no)
			(layer "F.Fab")
		)
		(pad "1" smd custom
			(at 0 -0.4445 90)
			(size 0.1397 0.1397)
			(layers "F.Cu" "F.Mask" "F.Paste")
			(net "P5VA_DIV")
			(options
				(clearance outline)
				(anchor circle)
			)
			(primitives
				(gr_poly
					(pts
						(arc
							(start -0.1778 -0.2794)
							(mid -0.249642 -0.249642)
							(end -0.2794 -0.1778)
						)
						(arc
							(start -0.2794 0.1778)
							(mid -0.249642 0.249642)
							(end -0.1778 0.2794)
						)
						(arc
							(start 0.1778 0.2794)
							(mid 0.249642 0.249642)
							(end 0.2794 0.1778)
						)
						(arc
							(start 0.2794 -0.1778)
							(mid 0.249642 -0.249642)
							(end 0.1778 -0.2794)
						)
					)
					(width 0)
					(fill yes)
				)
			)
		)
		(pad "2" smd custom
			(at 0 0.4445 90)
			(size 0.1397 0.1397)
			(layers "F.Cu" "F.Mask" "F.Paste")
			(net "P5VA_SENSE")
			(options
				(clearance outline)
				(anchor circle)
			)
			(primitives
				(gr_poly
					(pts
						(arc
							(start -0.1778 -0.2794)
							(mid -0.249642 -0.249642)
							(end -0.2794 -0.1778)
						)
						(arc
							(start -0.2794 0.1778)
							(mid -0.249642 0.249642)
							(end -0.1778 0.2794)
						)
						(arc
							(start 0.1778 0.2794)
							(mid 0.249642 0.249642)
							(end 0.2794 0.1778)
						)
						(arc
							(start 0.2794 -0.1778)
							(mid 0.249642 -0.249642)
							(end 0.1778 -0.2794)
						)
					)
					(width 0)
					(fill yes)
				)
			)
		)
	)
	(footprint ""
		(layer "F.Cu")
		(at 219.184982 -291.183568 180)
		(property "Reference" "C146"
			(at 0 0 180)
			(layer "F.SilkS")
			(hide yes)
			(effects
				(font
					(size 1.27 1.27)
				)
			)
		)
		(property "Value" "SC1U25V3KX-1-GP"
			(at 0 -2.8194 180)
			(unlocked yes)
			(layer "F.Fab")
			(hide yes)
			(effects
				(font
					(size 1.016 1.016)
					(thickness 0.1524)
				)
			)
		)
		(property "Device Type" "C603H36"
			(at 0 -4.3434 180)
			(unlocked yes)
			(layer "F.Fab")
			(hide yes)
			(effects
				(font
					(size 1.016 1.016)
					(thickness 0.1524)
				)
			)
		)
		(duplicate_pad_numbers_are_jumpers no)
		(fp_line
			(start 0.508 0)
			(end -0.508 0)
			(stroke
				(width 0.2032)
				(type default)
			)
			(layer "F.SilkS")
		)
		(fp_rect
			(start -0.5842 1.3335)
			(end 0.5842 -1.3335)
			(stroke
				(width 0)
				(type default)
			)
			(fill no)
			(layer "F.CrtYd")
		)
		(fp_rect
			(start -0.5842 1.3335)
			(end 0.5842 -1.3335)
			(stroke
				(width 0)
				(type default)
			)
			(fill no)
			(layer "F.Fab")
		)
		(pad "1" smd custom
			(at 0 -0.762 180)
			(size 0.2159 0.2159)
			(layers "F.Cu" "F.Mask" "F.Paste")
			(net "P12V_HDD2")
			(options
				(clearance outline)
				(anchor circle)
			)
			(primitives
				(gr_poly
					(pts
						(arc
							(start -0.3302 -0.4318)
							(mid -0.402042 -0.402042)
							(end -0.4318 -0.3302)
						)
						(arc
							(start -0.4318 0.3302)
							(mid -0.402042 0.402042)
							(end -0.3302 0.4318)
						)
						(arc
							(start 0.3302 0.4318)
							(mid 0.402042 0.402042)
							(end 0.4318 0.3302)
						)
						(arc
							(start 0.4318 -0.3302)
							(mid 0.402042 -0.402042)
							(end 0.3302 -0.4318)
						)
					)
					(width 0)
					(fill yes)
				)
			)
		)
		(pad "2" smd custom
			(at 0 0.762 180)
			(size 0.2159 0.2159)
			(layers "F.Cu" "F.Mask" "F.Paste")
			(net "GND")
			(options
				(clearance outline)
				(anchor circle)
			)
			(primitives
				(gr_poly
					(pts
						(arc
							(start -0.3302 -0.4318)
							(mid -0.402042 -0.402042)
							(end -0.4318 -0.3302)
						)
						(arc
							(start -0.4318 0.3302)
							(mid -0.402042 0.402042)
							(end -0.3302 0.4318)
						)
						(arc
							(start 0.3302 0.4318)
							(mid 0.402042 0.402042)
							(end 0.4318 0.3302)
						)
						(arc
							(start 0.4318 -0.3302)
							(mid 0.402042 -0.402042)
							(end 0.3302 -0.4318)
						)
					)
					(width 0)
					(fill yes)
				)
			)
		)
	)
)
